(kicad_pcb
	(version 20260206)
	(generator "pcbnew")
	(generator_version "10.0")
	(general
		(thickness 1.6)
		(legacy_teardrops no)
	)
	(paper "A4")
	(title_block
		(title "9054_F0T_PDB_BD_GPU_F_V04_1213_1550_OCP.brd")
		(comment 1 "Grand Teton / footprints 112-118 of 608")
	)
	(layers
		(0 "F.Cu" signal "TOP")
		(4 "In1.Cu" signal "GND")
		(6 "In2.Cu" signal "IN1")
		(8 "In3.Cu" signal "GND1")
		(10 "In4.Cu" signal "VCC")
		(12 "In5.Cu" signal "VCC1")
		(14 "In6.Cu" signal "GND2")
		(16 "In7.Cu" signal "IN2")
		(18 "In8.Cu" signal "GND3")
		(2 "B.Cu" signal "BOTTOM")
		(9 "F.Adhes" user "F.Adhesive")
		(11 "B.Adhes" user "B.Adhesive")
		(13 "F.Paste" user "Package Geometry/Pastemask Top")
		(15 "B.Paste" user "Package Geometry/Pastemask Bottom")
		(5 "F.SilkS" user "Ref Des/Silkscreen Top")
		(7 "B.SilkS" user "Ref Des/Silkscreen Bottom")
		(1 "F.Mask" user "Board Geometry/Soldermask Top")
		(3 "B.Mask" user "Board Geometry/Soldermask Bottom")
		(17 "Dwgs.User" user "User.Drawings")
		(19 "Cmts.User" user "User.Comments")
		(21 "Eco1.User" user "User.Eco1")
		(23 "Eco2.User" user "User.Eco2")
		(25 "Edge.Cuts" user "Board Geometry/Outline")
		(27 "Margin" user)
		(31 "F.CrtYd" user "Package Geometry/Place Bound Top")
		(29 "B.CrtYd" user "Package Geometry/Place Bound Bottom")
		(35 "F.Fab" user "Ref Des/Assembly Top")
		(33 "B.Fab" user "Ref Des/Assembly Bottom")
	)
	(footprint ""
		(layer "F.Cu")
		(at 467.909656 -107.502452 90)
		(property "Reference" "R84"
			(at 0 0 90)
			(layer "F.SilkS")
			(hide yes)
			(effects
				(font
					(size 1.27 1.27)
				)
			)
		)
		(property "Value" ""
			(at 0 0 90)
			(layer "F.Fab")
			(effects
				(font
					(size 1.27 1.27)
				)
			)
		)
		(duplicate_pad_numbers_are_jumpers no)
		(fp_line
			(start 0.7874 -0.4064)
			(end 0.7874 0.4064)
			(stroke
				(width 0.1524)
				(type default)
			)
			(layer "F.SilkS")
		)
		(fp_line
			(start -0.7874 -0.4064)
			(end 0.7874 -0.4064)
			(stroke
				(width 0.1524)
				(type default)
			)
			(layer "F.SilkS")
		)
		(fp_line
			(start 0.7874 0.4064)
			(end -0.7874 0.4064)
			(stroke
				(width 0.1524)
				(type default)
			)
			(layer "F.SilkS")
		)
		(fp_line
			(start -0.7874 0.4064)
			(end -0.7874 -0.4064)
			(stroke
				(width 0.1524)
				(type default)
			)
			(layer "F.SilkS")
		)
		(fp_line
			(start -0.12065 -0.305054)
			(end -0.12065 -0.2794)
			(stroke
				(width 0.1)
				(type default)
			)
			(layer "F.Fab")
		)
		(fp_line
			(start -0.67945 -0.305054)
			(end -0.12065 -0.305054)
			(stroke
				(width 0.1)
				(type default)
			)
			(layer "F.Fab")
		)
		(fp_line
			(start 0.67945 -0.3048)
			(end 0.67945 0.3048)
			(stroke
				(width 0.1)
				(type default)
			)
			(layer "F.Fab")
		)
		(fp_line
			(start 0.12065 -0.3048)
			(end 0.67945 -0.3048)
			(stroke
				(width 0.1)
				(type default)
			)
			(layer "F.Fab")
		)
		(fp_line
			(start 0.12065 -0.2794)
			(end 0.12065 -0.3048)
			(stroke
				(width 0.1)
				(type default)
			)
			(layer "F.Fab")
		)
		(fp_line
			(start -0.12065 -0.2794)
			(end 0.12065 -0.2794)
			(stroke
				(width 0.1)
				(type default)
			)
			(layer "F.Fab")
		)
		(fp_line
			(start 0.120396 0.2794)
			(end -0.12065 0.2794)
			(stroke
				(width 0.1)
				(type default)
			)
			(layer "F.Fab")
		)
		(fp_line
			(start -0.12065 0.2794)
			(end -0.12065 0.3048)
			(stroke
				(width 0.1)
				(type default)
			)
			(layer "F.Fab")
		)
		(fp_line
			(start 0.67945 0.3048)
			(end 0.120396 0.3048)
			(stroke
				(width 0.1)
				(type default)
			)
			(layer "F.Fab")
		)
		(fp_line
			(start 0.120396 0.3048)
			(end 0.120396 0.2794)
			(stroke
				(width 0.1)
				(type default)
			)
			(layer "F.Fab")
		)
		(fp_line
			(start -0.12065 0.3048)
			(end -0.67945 0.3048)
			(stroke
				(width 0.1)
				(type default)
			)
			(layer "F.Fab")
		)
		(fp_line
			(start -0.67945 0.3048)
			(end -0.67945 -0.305054)
			(stroke
				(width 0.1)
				(type default)
			)
			(layer "F.Fab")
		)
		(pad "1" smd circle
			(at -0.40005 0 90)
			(size 0 0)
			(layers "F.Cu" "F.Mask" "F.Paste")
			(net "SMB_PDB_SCL")
		)
		(pad "2" smd circle
			(at 0.40005 0 90)
			(size 0 0)
			(layers "F.Cu" "F.Mask" "F.Paste")
			(net "SMB_PDB_R_SCL")
		)
	)
	(footprint ""
		(layer "F.Cu")
		(at 406.273 -29.21 180)
		(property "Reference" "D1"
			(at 0.7366 -1.29667 0)
			(unlocked yes)
			(layer "F.SilkS")
			(effects
				(font
					(size 0.7874 0.5842)
					(thickness 0.1524)
				)
				(justify left)
			)
		)
		(property "Value" ""
			(at 0 0 180)
			(layer "F.Fab")
			(effects
				(font
					(size 1.27 1.27)
				)
			)
		)
		(duplicate_pad_numbers_are_jumpers no)
		(fp_line
			(start 1.16078 0.4826)
			(end -0.64008 0.4826)
			(stroke
				(width 0.1524)
				(type default)
			)
			(layer "F.SilkS")
		)
		(fp_line
			(start 1.16078 -0.4826)
			(end 1.16078 0.4826)
			(stroke
				(width 0.1524)
				(type default)
			)
			(layer "F.SilkS")
		)
		(fp_line
			(start 1.03378 0.4826)
			(end -0.79248 0.4826)
			(stroke
				(width 0.1524)
				(type default)
			)
			(layer "F.SilkS")
		)
		(fp_line
			(start 1.03378 -0.4826)
			(end 1.03378 0.4826)
			(stroke
				(width 0.1524)
				(type default)
			)
			(layer "F.SilkS")
		)
		(fp_line
			(start 0.90678 0.4826)
			(end -0.90678 0.4826)
			(stroke
				(width 0.1524)
				(type default)
			)
			(layer "F.SilkS")
		)
		(fp_line
			(start 0.90678 -0.4826)
			(end 0.90678 0.4826)
			(stroke
				(width 0.1524)
				(type default)
			)
			(layer "F.SilkS")
		)
		(fp_line
			(start -0.64008 -0.4826)
			(end 1.16078 -0.4826)
			(stroke
				(width 0.1524)
				(type default)
			)
			(layer "F.SilkS")
		)
		(fp_line
			(start -0.79248 -0.4826)
			(end 1.03378 -0.4826)
			(stroke
				(width 0.1524)
				(type default)
			)
			(layer "F.SilkS")
		)
		(fp_line
			(start -0.89408 -0.4826)
			(end 0.90678 -0.4826)
			(stroke
				(width 0.1524)
				(type default)
			)
			(layer "F.SilkS")
		)
		(fp_line
			(start -0.90678 0.4826)
			(end -0.90678 -0.4699)
			(stroke
				(width 0.1524)
				(type default)
			)
			(layer "F.SilkS")
		)
		(fp_line
			(start 0.499872 0.249936)
			(end -0.499872 0.249936)
			(stroke
				(width 0.1)
				(type default)
			)
			(layer "F.Fab")
		)
		(fp_line
			(start 0.499872 -0.249936)
			(end 0.499872 0.249936)
			(stroke
				(width 0.1)
				(type default)
			)
			(layer "F.Fab")
		)
		(fp_line
			(start -0.499872 0.249936)
			(end -0.499872 -0.249936)
			(stroke
				(width 0.1)
				(type default)
			)
			(layer "F.Fab")
		)
		(fp_line
			(start -0.499872 -0.249936)
			(end 0.499872 -0.249936)
			(stroke
				(width 0.1)
				(type default)
			)
			(layer "F.Fab")
		)
		(pad "A" smd rect
			(at -0.47498 0 180)
			(size 0.6096 0.7112)
			(layers "F.Cu" "F.Mask" "F.Paste")
			(net "LED_D1_R5")
		)
		(pad "C" smd rect
			(at 0.47498 0 180)
			(size 0.6096 0.7112)
			(layers "F.Cu" "F.Mask" "F.Paste")
			(net "GND")
		)
	)
	(footprint ""
		(layer "F.Cu")
		(at 449.3514 -29.591)
		(property "Reference" "R330"
			(at 0 0 0)
			(layer "F.SilkS")
			(hide yes)
			(effects
				(font
					(size 1.27 1.27)
				)
			)
		)
		(property "Value" ""
			(at 0 0 0)
			(layer "F.Fab")
			(effects
				(font
					(size 1.27 1.27)
				)
			)
		)
		(duplicate_pad_numbers_are_jumpers no)
		(fp_line
			(start -0.7874 -0.4064)
			(end 0.7874 -0.4064)
			(stroke
				(width 0.1524)
				(type default)
			)
			(layer "F.SilkS")
		)
		(fp_line
			(start -0.7874 0.4064)
			(end -0.7874 -0.4064)
			(stroke
				(width 0.1524)
				(type default)
			)
			(layer "F.SilkS")
		)
		(fp_line
			(start 0.7874 -0.4064)
			(end 0.7874 0.4064)
			(stroke
				(width 0.1524)
				(type default)
			)
			(layer "F.SilkS")
		)
		(fp_line
			(start 0.7874 0.4064)
			(end -0.7874 0.4064)
			(stroke
				(width 0.1524)
				(type default)
			)
			(layer "F.SilkS")
		)
		(fp_line
			(start -0.67945 -0.305054)
			(end -0.12065 -0.305054)
			(stroke
				(width 0.1)
				(type default)
			)
			(layer "F.Fab")
		)
		(fp_line
			(start -0.67945 0.3048)
			(end -0.67945 -0.305054)
			(stroke
				(width 0.1)
				(type default)
			)
			(layer "F.Fab")
		)
		(fp_line
			(start -0.12065 -0.305054)
			(end -0.12065 -0.2794)
			(stroke
				(width 0.1)
				(type default)
			)
			(layer "F.Fab")
		)
		(fp_line
			(start -0.12065 -0.2794)
			(end 0.12065 -0.2794)
			(stroke
				(width 0.1)
				(type default)
			)
			(layer "F.Fab")
		)
		(fp_line
			(start -0.12065 0.2794)
			(end -0.12065 0.3048)
			(stroke
				(width 0.1)
				(type default)
			)
			(layer "F.Fab")
		)
		(fp_line
			(start -0.12065 0.3048)
			(end -0.67945 0.3048)
			(stroke
				(width 0.1)
				(type default)
			)
			(layer "F.Fab")
		)
		(fp_line
			(start 0.120396 0.2794)
			(end -0.12065 0.2794)
			(stroke
				(width 0.1)
				(type default)
			)
			(layer "F.Fab")
		)
		(fp_line
			(start 0.120396 0.3048)
			(end 0.120396 0.2794)
			(stroke
				(width 0.1)
				(type default)
			)
			(layer "F.Fab")
		)
		(fp_line
			(start 0.12065 -0.3048)
			(end 0.67945 -0.3048)
			(stroke
				(width 0.1)
				(type default)
			)
			(layer "F.Fab")
		)
		(fp_line
			(start 0.12065 -0.2794)
			(end 0.12065 -0.3048)
			(stroke
				(width 0.1)
				(type default)
			)
			(layer "F.Fab")
		)
		(fp_line
			(start 0.67945 -0.3048)
			(end 0.67945 0.3048)
			(stroke
				(width 0.1)
				(type default)
			)
			(layer "F.Fab")
		)
		(fp_line
			(start 0.67945 0.3048)
			(end 0.120396 0.3048)
			(stroke
				(width 0.1)
				(type default)
			)
			(layer "F.Fab")
		)
		(pad "1" smd circle
			(at -0.40005 0)
			(size 0 0)
			(layers "F.Cu" "F.Mask" "F.Paste")
			(net "SMB_PDB_FAN_1_SCL")
		)
		(pad "2" smd circle
			(at 0.40005 0)
			(size 0 0)
			(layers "F.Cu" "F.Mask" "F.Paste")
			(net "P3V3_AUX")
		)
	)
	(footprint ""
		(layer "F.Cu")
		(at 411.099 -46.736 -90)
		(property "Reference" "R52"
			(at 0 0 270)
			(layer "F.SilkS")
			(hide yes)
			(effects
				(font
					(size 1.27 1.27)
				)
			)
		)
		(property "Value" ""
			(at 0 0 270)
			(layer "F.Fab")
			(effects
				(font
					(size 1.27 1.27)
				)
			)
		)
		(duplicate_pad_numbers_are_jumpers no)
		(fp_line
			(start -0.7874 0.4064)
			(end -0.7874 -0.4064)
			(stroke
				(width 0.1524)
				(type default)
			)
			(layer "F.SilkS")
		)
		(fp_line
			(start 0.7874 0.4064)
			(end -0.7874 0.4064)
			(stroke
				(width 0.1524)
				(type default)
			)
			(layer "F.SilkS")
		)
		(fp_line
			(start -0.7874 -0.4064)
			(end 0.7874 -0.4064)
			(stroke
				(width 0.1524)
				(type default)
			)
			(layer "F.SilkS")
		)
		(fp_line
			(start 0.7874 -0.4064)
			(end 0.7874 0.4064)
			(stroke
				(width 0.1524)
				(type default)
			)
			(layer "F.SilkS")
		)
		(fp_line
			(start -0.67945 0.3048)
			(end -0.67945 -0.305054)
			(stroke
				(width 0.1)
				(type default)
			)
			(layer "F.Fab")
		)
		(fp_line
			(start -0.12065 0.3048)
			(end -0.67945 0.3048)
			(stroke
				(width 0.1)
				(type default)
			)
			(layer "F.Fab")
		)
		(fp_line
			(start 0.120396 0.3048)
			(end 0.120396 0.2794)
			(stroke
				(width 0.1)
				(type default)
			)
			(layer "F.Fab")
		)
		(fp_line
			(start 0.67945 0.3048)
			(end 0.120396 0.3048)
			(stroke
				(width 0.1)
				(type default)
			)
			(layer "F.Fab")
		)
		(fp_line
			(start -0.12065 0.2794)
			(end -0.12065 0.3048)
			(stroke
				(width 0.1)
				(type default)
			)
			(layer "F.Fab")
		)
		(fp_line
			(start 0.120396 0.2794)
			(end -0.12065 0.2794)
			(stroke
				(width 0.1)
				(type default)
			)
			(layer "F.Fab")
		)
		(fp_line
			(start -0.12065 -0.2794)
			(end 0.12065 -0.2794)
			(stroke
				(width 0.1)
				(type default)
			)
			(layer "F.Fab")
		)
		(fp_line
			(start 0.12065 -0.2794)
			(end 0.12065 -0.3048)
			(stroke
				(width 0.1)
				(type default)
			)
			(layer "F.Fab")
		)
		(fp_line
			(start 0.12065 -0.3048)
			(end 0.67945 -0.3048)
			(stroke
				(width 0.1)
				(type default)
			)
			(layer "F.Fab")
		)
		(fp_line
			(start 0.67945 -0.3048)
			(end 0.67945 0.3048)
			(stroke
				(width 0.1)
				(type default)
			)
			(layer "F.Fab")
		)
		(fp_line
			(start -0.67945 -0.305054)
			(end -0.12065 -0.305054)
			(stroke
				(width 0.1)
				(type default)
			)
			(layer "F.Fab")
		)
		(fp_line
			(start -0.12065 -0.305054)
			(end -0.12065 -0.2794)
			(stroke
				(width 0.1)
				(type default)
			)
			(layer "F.Fab")
		)
		(pad "1" smd circle
			(at -0.40005 0 270)
			(size 0 0)
			(layers "F.Cu" "F.Mask" "F.Paste")
			(net "P3V3_AUX")
		)
		(pad "2" smd circle
			(at 0.40005 0 270)
			(size 0 0)
			(layers "F.Cu" "F.Mask" "F.Paste")
			(net "PCA9555_A1")
		)
	)
	(footprint ""
		(layer "F.Cu")
		(at 443.509908 -83.825842 90)
		(property "Reference" "PC55"
			(at 0 0 90)
			(layer "F.SilkS")
			(hide yes)
			(effects
				(font
					(size 1.27 1.27)
				)
			)
		)
		(property "Value" ""
			(at 0 0 90)
			(layer "F.Fab")
			(effects
				(font
					(size 1.27 1.27)
				)
			)
		)
		(duplicate_pad_numbers_are_jumpers no)
		(fp_line
			(start 0.7874 -0.4064)
			(end 0.7874 0.4064)
			(stroke
				(width 0.1524)
				(type default)
			)
			(layer "F.SilkS")
		)
		(fp_line
			(start -0.7874 -0.4064)
			(end 0.7874 -0.4064)
			(stroke
				(width 0.1524)
				(type default)
			)
			(layer "F.SilkS")
		)
		(fp_line
			(start 0.7874 0.4064)
			(end -0.7874 0.4064)
			(stroke
				(width 0.1524)
				(type default)
			)
			(layer "F.SilkS")
		)
		(fp_line
			(start -0.7874 0.4064)
			(end -0.7874 -0.4064)
			(stroke
				(width 0.1524)
				(type default)
			)
			(layer "F.SilkS")
		)
		(fp_line
			(start -0.12065 -0.305054)
			(end -0.12065 -0.2794)
			(stroke
				(width 0.1)
				(type default)
			)
			(layer "F.Fab")
		)
		(fp_line
			(start -0.67945 -0.305054)
			(end -0.12065 -0.305054)
			(stroke
				(width 0.1)
				(type default)
			)
			(layer "F.Fab")
		)
		(fp_line
			(start 0.67945 -0.3048)
			(end 0.67945 0.3048)
			(stroke
				(width 0.1)
				(type default)
			)
			(layer "F.Fab")
		)
		(fp_line
			(start 0.12065 -0.3048)
			(end 0.67945 -0.3048)
			(stroke
				(width 0.1)
				(type default)
			)
			(layer "F.Fab")
		)
		(fp_line
			(start 0.12065 -0.2794)
			(end 0.12065 -0.3048)
			(stroke
				(width 0.1)
				(type default)
			)
			(layer "F.Fab")
		)
		(fp_line
			(start -0.12065 -0.2794)
			(end 0.12065 -0.2794)
			(stroke
				(width 0.1)
				(type default)
			)
			(layer "F.Fab")
		)
		(fp_line
			(start 0.120396 0.2794)
			(end -0.12065 0.2794)
			(stroke
				(width 0.1)
				(type default)
			)
			(layer "F.Fab")
		)
		(fp_line
			(start -0.12065 0.2794)
			(end -0.12065 0.3048)
			(stroke
				(width 0.1)
				(type default)
			)
			(layer "F.Fab")
		)
		(fp_line
			(start 0.67945 0.3048)
			(end 0.120396 0.3048)
			(stroke
				(width 0.1)
				(type default)
			)
			(layer "F.Fab")
		)
		(fp_line
			(start 0.120396 0.3048)
			(end 0.120396 0.2794)
			(stroke
				(width 0.1)
				(type default)
			)
			(layer "F.Fab")
		)
		(fp_line
			(start -0.12065 0.3048)
			(end -0.67945 0.3048)
			(stroke
				(width 0.1)
				(type default)
			)
			(layer "F.Fab")
		)
		(fp_line
			(start -0.67945 0.3048)
			(end -0.67945 -0.305054)
			(stroke
				(width 0.1)
				(type default)
			)
			(layer "F.Fab")
		)
		(pad "1" smd circle
			(at -0.40005 0 90)
			(size 0 0)
			(layers "F.Cu" "F.Mask" "F.Paste")
			(net "P3V3_HPDB_VCC")
		)
		(pad "2" smd circle
			(at 0.40005 0 90)
			(size 0 0)
			(layers "F.Cu" "F.Mask" "F.Paste")
			(net "GND")
		)
	)
	(footprint ""
		(layer "F.Cu")
		(at 428.00016 -83.999832 180)
		(property "Reference" "H13"
			(at 1.00076 -5.286502 0)
			(unlocked yes)
			(layer "F.SilkS")
			(effects
				(font
					(size 0.7874 0.5842)
					(thickness 0.1524)
				)
				(justify left)
			)
		)
		(property "Value" ""
			(at 0 0 180)
			(layer "F.Fab")
			(effects
				(font
					(size 1.27 1.27)
				)
			)
		)
		(duplicate_pad_numbers_are_jumpers no)
		(pad "1" thru_hole oval
			(at 0 0 180)
			(size 9.017 14.0208)
			(drill 3.0226
				(offset 0 2.499868)
			)
			(layers "*.Cu" "*.Mask")
			(remove_unused_layers no)
			(net "GND")
			(clearance -1.500378)
			(padstack
				(mode front_inner_back)
				(layer "Inner"
					(shape circle)
					(size 0 0)
					(clearance 0)
				)
				(layer "B.Cu"
					(shape oval)
					(size 9.017 14.0208)
					(offset 0 2.499868)
					(clearance -1.500378)
				)
			)
		)
	)
	(footprint ""
		(layer "F.Cu")
		(at 391.0584 -33.02 -90)
		(property "Reference" "PR98"
			(at 0 0 270)
			(layer "F.SilkS")
			(hide yes)
			(effects
				(font
					(size 1.27 1.27)
				)
			)
		)
		(property "Value" ""
			(at 0 0 270)
			(layer "F.Fab")
			(effects
				(font
					(size 1.27 1.27)
				)
			)
		)
		(duplicate_pad_numbers_are_jumpers no)
		(fp_line
			(start -2.234946 0.9271)
			(end -2.234946 -0.9271)
			(stroke
				(width 0.1524)
				(type default)
			)
			(layer "F.SilkS")
		)
		(fp_line
			(start 2.234946 0.9271)
			(end -2.234946 0.9271)
			(stroke
				(width 0.1524)
				(type default)
			)
			(layer "F.SilkS")
		)
		(fp_line
			(start -2.234946 -0.9271)
			(end 2.234946 -0.9271)
			(stroke
				(width 0.1524)
				(type default)
			)
			(layer "F.SilkS")
		)
		(fp_line
			(start 2.234946 -0.9271)
			(end 2.234946 0.9271)
			(stroke
				(width 0.1524)
				(type default)
			)
			(layer "F.SilkS")
		)
		(fp_line
			(start -1.575054 0.824992)
			(end 1.575054 0.824992)
			(stroke
				(width 0.1)
				(type default)
			)
			(layer "F.Fab")
		)
		(fp_line
			(start 1.575054 0.824992)
			(end 1.575054 -0.824992)
			(stroke
				(width 0.1)
				(type default)
			)
			(layer "F.Fab")
		)
		(fp_line
			(start -1.575054 -0.824992)
			(end -1.575054 0.824992)
			(stroke
				(width 0.1)
				(type default)
			)
			(layer "F.Fab")
		)
		(fp_line
			(start 1.575054 -0.824992)
			(end -1.575054 -0.824992)
			(stroke
				(width 0.1)
				(type default)
			)
			(layer "F.Fab")
		)
		(pad "1" smd rect
			(at -1.599946 0 270)
			(size 1.016 1.6002)
			(layers "F.Cu" "F.Mask" "F.Paste")
			(net "P52V_HS1")
		)
		(pad "2" smd rect
			(at 1.599946 0 270)
			(size 1.016 1.6002)
			(layers "F.Cu" "F.Mask" "F.Paste")
			(net "P52V_HS1_EN_DISCHARGE_N")
		)
	)
)
